# T6G (Grand Teton) — schematic netlist excerpt (pin names and nets, part order shuffled) for the footprints in the layout excerpt that follows; sources: Cadence DE-HDL packaged netlist, KiCad conversion of 04192023_DAF0TMB3IC0_F0TG_MB_C_brd_V02_OCP.brd

R272  Q_RES  0 5% EMPTY  pkg 0402LF  page 81 : A = RST_CPU1_SYS_N ; B = FM_CPU1_SYS_RESET_N
R2925  Q_RES  49.9 1% CHIP  pkg 0402LF  page 130 : A = FM_GPU_PWR_EN_R1 ; B = FM_GPU_PWR_EN_R_BUF
R861  Q_RES  1K 1% CHIP  pkg 0201LF  page 342 : A = P1V8_CPU1_RT_1D ; B = RT_CPU1_P2_ADDR3

(kicad_pcb
	(version 20260206)
	(generator "pcbnew")
	(generator_version "10.0")
	(general
		(thickness 1.6)
		(legacy_teardrops no)
	)
	(paper "A4")
	(title_block
		(title "04192023_DAF0TMB3IC0_F0TG_MB_C_brd_V02_OCP.brd")
		(comment 1 "Grand Teton / footprints 261-263 of 8354")
	)
	(layers
		(0 "F.Cu" signal "TOP")
		(4 "In1.Cu" signal "GND")
		(6 "In2.Cu" signal "IN1")
		(8 "In3.Cu" signal "GND1")
		(10 "In4.Cu" signal "IN2")
		(12 "In5.Cu" signal "GND2")
		(14 "In6.Cu" signal "IN3")
		(16 "In7.Cu" signal "GND3")
		(18 "In8.Cu" signal "VCC")
		(20 "In9.Cu" signal "VCC1")
		(22 "In10.Cu" signal "GND4")
		(24 "In11.Cu" signal "IN4")
		(26 "In12.Cu" signal "GND5")
		(28 "In13.Cu" signal "IN5")
		(30 "In14.Cu" signal "GND6")
		(32 "In15.Cu" signal "IN6")
		(34 "In16.Cu" signal "GND7")
		(2 "B.Cu" signal "BOTTOM")
		(9 "F.Adhes" user "F.Adhesive")
		(11 "B.Adhes" user "B.Adhesive")
		(13 "F.Paste" user "Package Geometry/Pastemask Top")
		(15 "B.Paste" user "Package Geometry/Pastemask Bottom")
		(5 "F.SilkS" user "Ref Des/Silkscreen Top")
		(7 "B.SilkS" user "Ref Des/Silkscreen Bottom")
		(1 "F.Mask" user "Board Geometry/Soldermask Top")
		(3 "B.Mask" user "Board Geometry/Soldermask Bottom")
		(17 "Dwgs.User" user "User.Drawings")
		(19 "Cmts.User" user "User.Comments")
		(21 "Eco1.User" user "User.Eco1")
		(23 "Eco2.User" user "User.Eco2")
		(25 "Edge.Cuts" user "Board Geometry/Outline")
		(27 "Margin" user)
		(31 "F.CrtYd" user "Package Geometry/Place Bound Top")
		(29 "B.CrtYd" user "Package Geometry/Place Bound Bottom")
		(35 "F.Fab" user "Ref Des/Assembly Top")
		(33 "B.Fab" user "Ref Des/Assembly Bottom")
	)
	(footprint ""
		(layer "F.Cu")
		(at 180.975 -129.377948 -90)
		(property "Reference" "R272"
			(at 0 0 270)
			(layer "F.SilkS")
			(hide yes)
			(effects
				(font
					(size 1.27 1.27)
				)
			)
		)
		(property "Value" ""
			(at 0 0 270)
			(layer "F.Fab")
			(effects
				(font
					(size 1.27 1.27)
				)
			)
		)
		(duplicate_pad_numbers_are_jumpers no)
		(fp_line
			(start -0.7874 0.4064)
			(end -0.7874 -0.4064)
			(stroke
				(width 0.1524)
				(type default)
			)
			(layer "F.SilkS")
		)
		(fp_line
			(start 0.7874 0.4064)
			(end -0.7874 0.4064)
			(stroke
				(width 0.1524)
				(type default)
			)
			(layer "F.SilkS")
		)
		(fp_line
			(start -0.7874 -0.4064)
			(end 0.7874 -0.4064)
			(stroke
				(width 0.1524)
				(type default)
			)
			(layer "F.SilkS")
		)
		(fp_line
			(start 0.7874 -0.4064)
			(end 0.7874 0.4064)
			(stroke
				(width 0.1524)
				(type default)
			)
			(layer "F.SilkS")
		)
		(fp_line
			(start -0.67945 0.3048)
			(end -0.67945 -0.305054)
			(stroke
				(width 0.1)
				(type default)
			)
			(layer "F.Fab")
		)
		(fp_line
			(start -0.12065 0.3048)
			(end -0.67945 0.3048)
			(stroke
				(width 0.1)
				(type default)
			)
			(layer "F.Fab")
		)
		(fp_line
			(start 0.120396 0.3048)
			(end 0.120396 0.2794)
			(stroke
				(width 0.1)
				(type default)
			)
			(layer "F.Fab")
		)
		(fp_line
			(start 0.67945 0.3048)
			(end 0.120396 0.3048)
			(stroke
				(width 0.1)
				(type default)
			)
			(layer "F.Fab")
		)
		(fp_line
			(start -0.12065 0.2794)
			(end -0.12065 0.3048)
			(stroke
				(width 0.1)
				(type default)
			)
			(layer "F.Fab")
		)
		(fp_line
			(start 0.120396 0.2794)
			(end -0.12065 0.2794)
			(stroke
				(width 0.1)
				(type default)
			)
			(layer "F.Fab")
		)
		(fp_line
			(start -0.12065 -0.2794)
			(end 0.12065 -0.2794)
			(stroke
				(width 0.1)
				(type default)
			)
			(layer "F.Fab")
		)
		(fp_line
			(start 0.12065 -0.2794)
			(end 0.12065 -0.3048)
			(stroke
				(width 0.1)
				(type default)
			)
			(layer "F.Fab")
		)
		(fp_line
			(start 0.12065 -0.3048)
			(end 0.67945 -0.3048)
			(stroke
				(width 0.1)
				(type default)
			)
			(layer "F.Fab")
		)
		(fp_line
			(start 0.67945 -0.3048)
			(end 0.67945 0.3048)
			(stroke
				(width 0.1)
				(type default)
			)
			(layer "F.Fab")
		)
		(fp_line
			(start -0.67945 -0.305054)
			(end -0.12065 -0.305054)
			(stroke
				(width 0.1)
				(type default)
			)
			(layer "F.Fab")
		)
		(fp_line
			(start -0.12065 -0.305054)
			(end -0.12065 -0.2794)
			(stroke
				(width 0.1)
				(type default)
			)
			(layer "F.Fab")
		)
		(pad "1" smd circle
			(at -0.40005 0 270)
			(size 0 0)
			(layers "F.Cu" "F.Mask" "F.Paste")
			(net "RST_CPU1_SYS_N")
		)
		(pad "2" smd circle
			(at 0.40005 0 270)
			(size 0 0)
			(layers "F.Cu" "F.Mask" "F.Paste")
			(net "FM_CPU1_SYS_RESET_N")
		)
	)
	(footprint ""
		(layer "F.Cu")
		(at 48.19904 -438.753504 90)
		(property "Reference" "R2925"
			(at 0 0 90)
			(layer "F.SilkS")
			(hide yes)
			(effects
				(font
					(size 1.27 1.27)
				)
			)
		)
		(property "Value" ""
			(at 0 0 90)
			(layer "F.Fab")
			(effects
				(font
					(size 1.27 1.27)
				)
			)
		)
		(duplicate_pad_numbers_are_jumpers no)
		(fp_line
			(start 0.7874 -0.4064)
			(end 0.7874 0.4064)
			(stroke
				(width 0.1524)
				(type default)
			)
			(layer "F.SilkS")
		)
		(fp_line
			(start -0.7874 -0.4064)
			(end 0.7874 -0.4064)
			(stroke
				(width 0.1524)
				(type default)
			)
			(layer "F.SilkS")
		)
		(fp_line
			(start 0.7874 0.4064)
			(end -0.7874 0.4064)
			(stroke
				(width 0.1524)
				(type default)
			)
			(layer "F.SilkS")
		)
		(fp_line
			(start -0.7874 0.4064)
			(end -0.7874 -0.4064)
			(stroke
				(width 0.1524)
				(type default)
			)
			(layer "F.SilkS")
		)
		(fp_line
			(start -0.12065 -0.305054)
			(end -0.12065 -0.2794)
			(stroke
				(width 0.1)
				(type default)
			)
			(layer "F.Fab")
		)
		(fp_line
			(start -0.67945 -0.305054)
			(end -0.12065 -0.305054)
			(stroke
				(width 0.1)
				(type default)
			)
			(layer "F.Fab")
		)
		(fp_line
			(start 0.67945 -0.3048)
			(end 0.67945 0.3048)
			(stroke
				(width 0.1)
				(type default)
			)
			(layer "F.Fab")
		)
		(fp_line
			(start 0.12065 -0.3048)
			(end 0.67945 -0.3048)
			(stroke
				(width 0.1)
				(type default)
			)
			(layer "F.Fab")
		)
		(fp_line
			(start 0.12065 -0.2794)
			(end 0.12065 -0.3048)
			(stroke
				(width 0.1)
				(type default)
			)
			(layer "F.Fab")
		)
		(fp_line
			(start -0.12065 -0.2794)
			(end 0.12065 -0.2794)
			(stroke
				(width 0.1)
				(type default)
			)
			(layer "F.Fab")
		)
		(fp_line
			(start 0.120396 0.2794)
			(end -0.12065 0.2794)
			(stroke
				(width 0.1)
				(type default)
			)
			(layer "F.Fab")
		)
		(fp_line
			(start -0.12065 0.2794)
			(end -0.12065 0.3048)
			(stroke
				(width 0.1)
				(type default)
			)
			(layer "F.Fab")
		)
		(fp_line
			(start 0.67945 0.3048)
			(end 0.120396 0.3048)
			(stroke
				(width 0.1)
				(type default)
			)
			(layer "F.Fab")
		)
		(fp_line
			(start 0.120396 0.3048)
			(end 0.120396 0.2794)
			(stroke
				(width 0.1)
				(type default)
			)
			(layer "F.Fab")
		)
		(fp_line
			(start -0.12065 0.3048)
			(end -0.67945 0.3048)
			(stroke
				(width 0.1)
				(type default)
			)
			(layer "F.Fab")
		)
		(fp_line
			(start -0.67945 0.3048)
			(end -0.67945 -0.305054)
			(stroke
				(width 0.1)
				(type default)
			)
			(layer "F.Fab")
		)
		(pad "1" smd circle
			(at -0.40005 0 90)
			(size 0 0)
			(layers "F.Cu" "F.Mask" "F.Paste")
			(net "FM_GPU_PWR_EN_R1")
		)
		(pad "2" smd circle
			(at 0.40005 0 90)
			(size 0 0)
			(layers "F.Cu" "F.Mask" "F.Paste")
			(net "FM_GPU_PWR_EN_R_BUF")
		)
	)
	(footprint ""
		(layer "F.Cu")
		(at 175.300894 -390.53008 180)
		(property "Reference" "R861"
			(at 0 0 180)
			(layer "F.SilkS")
			(hide yes)
			(effects
				(font
					(size 1.27 1.27)
				)
			)
		)
		(property "Value" ""
			(at 0 0 180)
			(layer "F.Fab")
			(effects
				(font
					(size 1.27 1.27)
				)
			)
		)
		(duplicate_pad_numbers_are_jumpers no)
		(fp_line
			(start 0.32512 0.175006)
			(end -0.32512 0.175006)
			(stroke
				(width 0.1)
				(type default)
			)
			(layer "F.Fab")
		)
		(fp_line
			(start 0.32512 -0.175006)
			(end 0.32512 0.175006)
			(stroke
				(width 0.1)
				(type default)
			)
			(layer "F.Fab")
		)
		(fp_line
			(start -0.32512 0.175006)
			(end -0.32512 -0.175006)
			(stroke
				(width 0.1)
				(type default)
			)
			(layer "F.Fab")
		)
		(fp_line
			(start -0.32512 -0.175006)
			(end 0.32512 -0.175006)
			(stroke
				(width 0.1)
				(type default)
			)
			(layer "F.Fab")
		)
		(pad "1" smd rect
			(at -0.2667 0 180)
			(size 0.3048 0.381)
			(layers "F.Cu" "F.Mask" "F.Paste")
			(net "P1V8_CPU1_RT_1D")
		)
		(pad "2" smd rect
			(at 0.2667 0)
			(size 0.3048 0.381)
			(layers "F.Cu" "F.Mask" "F.Paste")
			(net "RT_CPU1_P2_ADDR3")
		)
	)
)
